# S9S_MB_2U (Grand Teton) — schematic netlist excerpt (pin names and nets, part order shuffled) for the footprints in the layout excerpt that follows; sources: Cadence DE-HDL packaged netlist, KiCad conversion of 03242023_DA0F0TMBIJ0_F0T_Motherboard_J_brd_V01_OCP.brd

PC2281  Q_CAP  0.047UF 25V 10% X7R  pkg C0402  page 193 : A = P12V_E1S_SS_0 ; B = GND
R2506  Q_RES  1K 1% CHIP  pkg 0402LF  page 239 : A = P3V3_AUX ; B = JTAG_BMC_DBP_TMS

(kicad_pcb
	(version 20260206)
	(generator "pcbnew")
	(generator_version "10.0")
	(general
		(thickness 1.6)
		(legacy_teardrops no)
	)
	(paper "A4")
	(title_block
		(title "03242023_DA0F0TMBIJ0_F0T_Motherboard_J_brd_V01_OCP.brd")
		(comment 1 "Grand Teton / footprints 34-35 of 6105")
	)
	(layers
		(0 "F.Cu" signal "TOP")
		(4 "In1.Cu" signal "GND")
		(6 "In2.Cu" signal "IN1")
		(8 "In3.Cu" signal "GND1")
		(10 "In4.Cu" signal "IN2")
		(12 "In5.Cu" signal "GND2")
		(14 "In6.Cu" signal "IN3")
		(16 "In7.Cu" signal "GND3")
		(18 "In8.Cu" signal "VCC")
		(20 "In9.Cu" signal "VCC1")
		(22 "In10.Cu" signal "GND4")
		(24 "In11.Cu" signal "IN4")
		(26 "In12.Cu" signal "GND5")
		(28 "In13.Cu" signal "IN5")
		(30 "In14.Cu" signal "GND6")
		(32 "In15.Cu" signal "IN6")
		(34 "In16.Cu" signal "GND7")
		(2 "B.Cu" signal "BOTTOM")
		(9 "F.Adhes" user "F.Adhesive")
		(11 "B.Adhes" user "B.Adhesive")
		(13 "F.Paste" user "Package Geometry/Pastemask Top")
		(15 "B.Paste" user "Package Geometry/Pastemask Bottom")
		(5 "F.SilkS" user "Ref Des/Silkscreen Top")
		(7 "B.SilkS" user "Ref Des/Silkscreen Bottom")
		(1 "F.Mask" user "Board Geometry/Soldermask Top")
		(3 "B.Mask" user "Board Geometry/Soldermask Bottom")
		(17 "Dwgs.User" user "User.Drawings")
		(19 "Cmts.User" user "User.Comments")
		(21 "Eco1.User" user "User.Eco1")
		(23 "Eco2.User" user "User.Eco2")
		(25 "Edge.Cuts" user "Board Geometry/Outline")
		(27 "Margin" user)
		(31 "F.CrtYd" user "Package Geometry/Place Bound Top")
		(29 "B.CrtYd" user "Package Geometry/Place Bound Bottom")
		(35 "F.Fab" user "Ref Des/Assembly Top")
		(33 "B.Fab" user "Ref Des/Assembly Bottom")
	)
	(footprint ""
		(layer "F.Cu")
		(at 122.301 -75.021948 90)
		(property "Reference" "R2506"
			(at 0 0 90)
			(layer "F.SilkS")
			(hide yes)
			(effects
				(font
					(size 1.27 1.27)
				)
			)
		)
		(property "Value" ""
			(at 0 0 90)
			(layer "F.Fab")
			(effects
				(font
					(size 1.27 1.27)
				)
			)
		)
		(duplicate_pad_numbers_are_jumpers no)
		(fp_line
			(start 0.7874 -0.4064)
			(end 0.7874 0.4064)
			(stroke
				(width 0.1524)
				(type default)
			)
			(layer "F.SilkS")
		)
		(fp_line
			(start -0.7874 -0.4064)
			(end 0.7874 -0.4064)
			(stroke
				(width 0.1524)
				(type default)
			)
			(layer "F.SilkS")
		)
		(fp_line
			(start 0.7874 0.4064)
			(end -0.7874 0.4064)
			(stroke
				(width 0.1524)
				(type default)
			)
			(layer "F.SilkS")
		)
		(fp_line
			(start -0.7874 0.4064)
			(end -0.7874 -0.4064)
			(stroke
				(width 0.1524)
				(type default)
			)
			(layer "F.SilkS")
		)
		(fp_line
			(start -0.12065 -0.305054)
			(end -0.12065 -0.2794)
			(stroke
				(width 0.1)
				(type default)
			)
			(layer "F.Fab")
		)
		(fp_line
			(start -0.67945 -0.305054)
			(end -0.12065 -0.305054)
			(stroke
				(width 0.1)
				(type default)
			)
			(layer "F.Fab")
		)
		(fp_line
			(start 0.67945 -0.3048)
			(end 0.67945 0.3048)
			(stroke
				(width 0.1)
				(type default)
			)
			(layer "F.Fab")
		)
		(fp_line
			(start 0.12065 -0.3048)
			(end 0.67945 -0.3048)
			(stroke
				(width 0.1)
				(type default)
			)
			(layer "F.Fab")
		)
		(fp_line
			(start 0.12065 -0.2794)
			(end 0.12065 -0.3048)
			(stroke
				(width 0.1)
				(type default)
			)
			(layer "F.Fab")
		)
		(fp_line
			(start -0.12065 -0.2794)
			(end 0.12065 -0.2794)
			(stroke
				(width 0.1)
				(type default)
			)
			(layer "F.Fab")
		)
		(fp_line
			(start 0.120396 0.2794)
			(end -0.12065 0.2794)
			(stroke
				(width 0.1)
				(type default)
			)
			(layer "F.Fab")
		)
		(fp_line
			(start -0.12065 0.2794)
			(end -0.12065 0.3048)
			(stroke
				(width 0.1)
				(type default)
			)
			(layer "F.Fab")
		)
		(fp_line
			(start 0.67945 0.3048)
			(end 0.120396 0.3048)
			(stroke
				(width 0.1)
				(type default)
			)
			(layer "F.Fab")
		)
		(fp_line
			(start 0.120396 0.3048)
			(end 0.120396 0.2794)
			(stroke
				(width 0.1)
				(type default)
			)
			(layer "F.Fab")
		)
		(fp_line
			(start -0.12065 0.3048)
			(end -0.67945 0.3048)
			(stroke
				(width 0.1)
				(type default)
			)
			(layer "F.Fab")
		)
		(fp_line
			(start -0.67945 0.3048)
			(end -0.67945 -0.305054)
			(stroke
				(width 0.1)
				(type default)
			)
			(layer "F.Fab")
		)
		(pad "1" smd circle
			(at -0.40005 0 90)
			(size 0 0)
			(layers "F.Cu" "F.Mask" "F.Paste")
			(net "P3V3_AUX")
		)
		(pad "2" smd circle
			(at 0.40005 0 90)
			(size 0 0)
			(layers "F.Cu" "F.Mask" "F.Paste")
			(net "JTAG_BMC_DBP_TMS")
		)
	)
	(footprint ""
		(layer "F.Cu")
		(at 257.85953 -51.669442)
		(property "Reference" "PC2281"
			(at 0 0 0)
			(layer "F.SilkS")
			(hide yes)
			(effects
				(font
					(size 1.27 1.27)
				)
			)
		)
		(property "Value" ""
			(at 0 0 0)
			(layer "F.Fab")
			(effects
				(font
					(size 1.27 1.27)
				)
			)
		)
		(duplicate_pad_numbers_are_jumpers no)
		(fp_line
			(start -0.7874 -0.4064)
			(end 0.7874 -0.4064)
			(stroke
				(width 0.1524)
				(type default)
			)
			(layer "F.SilkS")
		)
		(fp_line
			(start -0.7874 0.4064)
			(end -0.7874 -0.4064)
			(stroke
				(width 0.1524)
				(type default)
			)
			(layer "F.SilkS")
		)
		(fp_line
			(start 0.7874 -0.4064)
			(end 0.7874 0.4064)
			(stroke
				(width 0.1524)
				(type default)
			)
			(layer "F.SilkS")
		)
		(fp_line
			(start 0.7874 0.4064)
			(end -0.7874 0.4064)
			(stroke
				(width 0.1524)
				(type default)
			)
			(layer "F.SilkS")
		)
		(fp_line
			(start -0.67945 -0.305054)
			(end -0.12065 -0.305054)
			(stroke
				(width 0.1)
				(type default)
			)
			(layer "F.Fab")
		)
		(fp_line
			(start -0.67945 0.3048)
			(end -0.67945 -0.305054)
			(stroke
				(width 0.1)
				(type default)
			)
			(layer "F.Fab")
		)
		(fp_line
			(start -0.12065 -0.305054)
			(end -0.12065 -0.2794)
			(stroke
				(width 0.1)
				(type default)
			)
			(layer "F.Fab")
		)
		(fp_line
			(start -0.12065 -0.2794)
			(end 0.12065 -0.2794)
			(stroke
				(width 0.1)
				(type default)
			)
			(layer "F.Fab")
		)
		(fp_line
			(start -0.12065 0.2794)
			(end -0.12065 0.3048)
			(stroke
				(width 0.1)
				(type default)
			)
			(layer "F.Fab")
		)
		(fp_line
			(start -0.12065 0.3048)
			(end -0.67945 0.3048)
			(stroke
				(width 0.1)
				(type default)
			)
			(layer "F.Fab")
		)
		(fp_line
			(start 0.120396 0.2794)
			(end -0.12065 0.2794)
			(stroke
				(width 0.1)
				(type default)
			)
			(layer "F.Fab")
		)
		(fp_line
			(start 0.120396 0.3048)
			(end 0.120396 0.2794)
			(stroke
				(width 0.1)
				(type default)
			)
			(layer "F.Fab")
		)
		(fp_line
			(start 0.12065 -0.3048)
			(end 0.67945 -0.3048)
			(stroke
				(width 0.1)
				(type default)
			)
			(layer "F.Fab")
		)
		(fp_line
			(start 0.12065 -0.2794)
			(end 0.12065 -0.3048)
			(stroke
				(width 0.1)
				(type default)
			)
			(layer "F.Fab")
		)
		(fp_line
			(start 0.67945 -0.3048)
			(end 0.67945 0.3048)
			(stroke
				(width 0.1)
				(type default)
			)
			(layer "F.Fab")
		)
		(fp_line
			(start 0.67945 0.3048)
			(end 0.120396 0.3048)
			(stroke
				(width 0.1)
				(type default)
			)
			(layer "F.Fab")
		)
		(pad "1" smd circle
			(at -0.40005 0)
			(size 0 0)
			(layers "F.Cu" "F.Mask" "F.Paste")
			(net "P12V_E1S_SS_0")
		)
		(pad "2" smd circle
			(at 0.40005 0)
			(size 0 0)
			(layers "F.Cu" "F.Mask" "F.Paste")
			(net "GND")
		)
	)
)
